# S9S_MB_2U (Grand Teton) — schematic netlist excerpt (pin names and nets, part order shuffled) for the footprints in the layout excerpt that follows; sources: Cadence DE-HDL packaged netlist, KiCad conversion of 03242023_DA0F0TMBIJ0_F0T_Motherboard_J_brd_V01_OCP.brd

C2328  Q_CAP  10UF 6.3V 20% X6S  pkg C0603  page 211 : A = P3V3_9ZXL045_VDD ; B = GND
R2421  Q_RES  33.2 1% CHIP  pkg 0402LF  page 240 : A = SMB_VR_SENSOR_3V3AUX_SCL ; B = SMB_VR_3V3AUX_SCL_R0
C31  Q_CAP  10UF 16V 10% X6S  pkg C0805  page 91 : A = P12V_S3_AUX_CPU0_NVDIMM ; B = GND

(kicad_pcb
	(version 20260206)
	(generator "pcbnew")
	(generator_version "10.0")
	(general
		(thickness 1.6)
		(legacy_teardrops no)
	)
	(paper "A4")
	(title_block
		(title "03242023_DA0F0TMBIJ0_F0T_Motherboard_J_brd_V01_OCP.brd")
		(comment 1 "Grand Teton / footprints 5001-5003 of 6105")
	)
	(layers
		(0 "F.Cu" signal "TOP")
		(4 "In1.Cu" signal "GND")
		(6 "In2.Cu" signal "IN1")
		(8 "In3.Cu" signal "GND1")
		(10 "In4.Cu" signal "IN2")
		(12 "In5.Cu" signal "GND2")
		(14 "In6.Cu" signal "IN3")
		(16 "In7.Cu" signal "GND3")
		(18 "In8.Cu" signal "VCC")
		(20 "In9.Cu" signal "VCC1")
		(22 "In10.Cu" signal "GND4")
		(24 "In11.Cu" signal "IN4")
		(26 "In12.Cu" signal "GND5")
		(28 "In13.Cu" signal "IN5")
		(30 "In14.Cu" signal "GND6")
		(32 "In15.Cu" signal "IN6")
		(34 "In16.Cu" signal "GND7")
		(2 "B.Cu" signal "BOTTOM")
		(9 "F.Adhes" user "F.Adhesive")
		(11 "B.Adhes" user "B.Adhesive")
		(13 "F.Paste" user "Package Geometry/Pastemask Top")
		(15 "B.Paste" user "Package Geometry/Pastemask Bottom")
		(5 "F.SilkS" user "Ref Des/Silkscreen Top")
		(7 "B.SilkS" user "Ref Des/Silkscreen Bottom")
		(1 "F.Mask" user "Board Geometry/Soldermask Top")
		(3 "B.Mask" user "Board Geometry/Soldermask Bottom")
		(17 "Dwgs.User" user "User.Drawings")
		(19 "Cmts.User" user "User.Comments")
		(21 "Eco1.User" user "User.Eco1")
		(23 "Eco2.User" user "User.Eco2")
		(25 "Edge.Cuts" user "Board Geometry/Outline")
		(27 "Margin" user)
		(31 "F.CrtYd" user "Package Geometry/Place Bound Top")
		(29 "B.CrtYd" user "Package Geometry/Place Bound Bottom")
		(35 "F.Fab" user "Ref Des/Assembly Top")
		(33 "B.Fab" user "Ref Des/Assembly Bottom")
	)
	(footprint ""
		(layer "B.Cu")
		(at 111.31677 -409.467558 90)
		(property "Reference" "C2328"
			(at 0 0 90)
			(layer "B.SilkS")
			(hide yes)
			(effects
				(font
					(size 1.27 1.27)
				)
				(justify mirror)
			)
		)
		(property "Value" ""
			(at 0 0 90)
			(layer "B.Fab")
			(effects
				(font
					(size 1.27 1.27)
				)
				(justify mirror)
			)
		)
		(duplicate_pad_numbers_are_jumpers no)
		(fp_line
			(start 1.2954 -0.5842)
			(end -1.2954 -0.5842)
			(stroke
				(width 0.1524)
				(type default)
			)
			(layer "B.SilkS")
		)
		(fp_line
			(start 0 -0.5842)
			(end 0 0.5842)
			(stroke
				(width 0.1524)
				(type default)
			)
			(layer "B.SilkS")
		)
		(fp_line
			(start -1.2954 -0.5842)
			(end -1.2954 0.5842)
			(stroke
				(width 0.1524)
				(type default)
			)
			(layer "B.SilkS")
		)
		(fp_line
			(start 1.2954 0.5842)
			(end 1.2954 -0.5842)
			(stroke
				(width 0.1524)
				(type default)
			)
			(layer "B.SilkS")
		)
		(fp_line
			(start -1.2954 0.5842)
			(end 1.2954 0.5842)
			(stroke
				(width 0.1524)
				(type default)
			)
			(layer "B.SilkS")
		)
		(fp_line
			(start 0.8636 -0.4572)
			(end -0.8636 -0.4572)
			(stroke
				(width 0.1)
				(type default)
			)
			(layer "B.Fab")
		)
		(fp_line
			(start -0.8636 -0.4572)
			(end -0.8636 -0.4064)
			(stroke
				(width 0.1)
				(type default)
			)
			(layer "B.Fab")
		)
		(fp_line
			(start 1.1938 -0.4064)
			(end 0.8636 -0.4064)
			(stroke
				(width 0.1)
				(type default)
			)
			(layer "B.Fab")
		)
		(fp_line
			(start 0.8636 -0.4064)
			(end 0.8636 -0.4572)
			(stroke
				(width 0.1)
				(type default)
			)
			(layer "B.Fab")
		)
		(fp_line
			(start -0.8636 -0.4064)
			(end -1.1938 -0.4064)
			(stroke
				(width 0.1)
				(type default)
			)
			(layer "B.Fab")
		)
		(fp_line
			(start -1.1938 -0.4064)
			(end -1.1938 0.4064)
			(stroke
				(width 0.1)
				(type default)
			)
			(layer "B.Fab")
		)
		(fp_line
			(start 1.1938 0.4064)
			(end 1.1938 -0.4064)
			(stroke
				(width 0.1)
				(type default)
			)
			(layer "B.Fab")
		)
		(fp_line
			(start 0.8636 0.4064)
			(end 1.1938 0.4064)
			(stroke
				(width 0.1)
				(type default)
			)
			(layer "B.Fab")
		)
		(fp_line
			(start -0.8636 0.4064)
			(end -0.8636 0.4572)
			(stroke
				(width 0.1)
				(type default)
			)
			(layer "B.Fab")
		)
		(fp_line
			(start -1.1938 0.4064)
			(end -0.8636 0.4064)
			(stroke
				(width 0.1)
				(type default)
			)
			(layer "B.Fab")
		)
		(fp_line
			(start 0.8636 0.4572)
			(end 0.8636 0.4064)
			(stroke
				(width 0.1)
				(type default)
			)
			(layer "B.Fab")
		)
		(fp_line
			(start -0.8636 0.4572)
			(end 0.8636 0.4572)
			(stroke
				(width 0.1)
				(type default)
			)
			(layer "B.Fab")
		)
		(pad "1" smd rect
			(at 0.7366 0)
			(size 0.7112 0.8128)
			(layers "B.Cu" "B.Mask" "B.Paste")
			(net "P3V3_9ZXL045_VDD")
		)
		(pad "2" smd rect
			(at -0.7366 0)
			(size 0.7112 0.8128)
			(layers "B.Cu" "B.Mask" "B.Paste")
			(net "GND")
		)
	)
	(footprint ""
		(layer "B.Cu")
		(at 406.766014 -321.549776 -90)
		(property "Reference" "C31"
			(at 0 0 90)
			(layer "B.SilkS")
			(hide yes)
			(effects
				(font
					(size 1.27 1.27)
				)
				(justify mirror)
			)
		)
		(property "Value" ""
			(at 0 0 90)
			(layer "B.Fab")
			(effects
				(font
					(size 1.27 1.27)
				)
				(justify mirror)
			)
		)
		(duplicate_pad_numbers_are_jumpers no)
		(fp_line
			(start -1.524 0.762)
			(end 1.524 0.762)
			(stroke
				(width 0.1524)
				(type default)
			)
			(layer "B.SilkS")
		)
		(fp_line
			(start 1.524 0.762)
			(end 1.524 -0.762)
			(stroke
				(width 0.1524)
				(type default)
			)
			(layer "B.SilkS")
		)
		(fp_line
			(start -1.524 -0.762)
			(end -1.524 0.762)
			(stroke
				(width 0.1524)
				(type default)
			)
			(layer "B.SilkS")
		)
		(fp_line
			(start 1.524 -0.762)
			(end -1.524 -0.762)
			(stroke
				(width 0.1524)
				(type default)
			)
			(layer "B.SilkS")
		)
		(fp_line
			(start -1.1049 0.724916)
			(end -1.1049 -0.724916)
			(stroke
				(width 0.1)
				(type default)
			)
			(layer "B.Fab")
		)
		(fp_line
			(start 1.1049 0.724916)
			(end -1.1049 0.724916)
			(stroke
				(width 0.1)
				(type default)
			)
			(layer "B.Fab")
		)
		(fp_line
			(start -1.1049 -0.724916)
			(end 1.1049 -0.724916)
			(stroke
				(width 0.1)
				(type default)
			)
			(layer "B.Fab")
		)
		(fp_line
			(start 1.1049 -0.724916)
			(end 1.1049 0.724916)
			(stroke
				(width 0.1)
				(type default)
			)
			(layer "B.Fab")
		)
		(pad "1" smd rect
			(at 0.889 0 270)
			(size 1.016 1.27)
			(layers "B.Cu" "B.Mask" "B.Paste")
			(net "P12V_S3_AUX_CPU0_NVDIMM")
		)
		(pad "2" smd rect
			(at -0.889 0 270)
			(size 1.016 1.27)
			(layers "B.Cu" "B.Mask" "B.Paste")
			(net "GND")
		)
	)
	(footprint ""
		(layer "B.Cu")
		(at 180.814218 -13.772388 90)
		(property "Reference" "R2421"
			(at 0 0 90)
			(layer "B.SilkS")
			(hide yes)
			(effects
				(font
					(size 1.27 1.27)
				)
				(justify mirror)
			)
		)
		(property "Value" ""
			(at 0 0 90)
			(layer "B.Fab")
			(effects
				(font
					(size 1.27 1.27)
				)
				(justify mirror)
			)
		)
		(duplicate_pad_numbers_are_jumpers no)
		(fp_line
			(start 0.7874 -0.4064)
			(end -0.7874 -0.4064)
			(stroke
				(width 0.1524)
				(type default)
			)
			(layer "B.SilkS")
		)
		(fp_line
			(start -0.7874 -0.4064)
			(end -0.7874 0.4064)
			(stroke
				(width 0.1524)
				(type default)
			)
			(layer "B.SilkS")
		)
		(fp_line
			(start 0.7874 0.4064)
			(end 0.7874 -0.4064)
			(stroke
				(width 0.1524)
				(type default)
			)
			(layer "B.SilkS")
		)
		(fp_line
			(start -0.7874 0.4064)
			(end 0.7874 0.4064)
			(stroke
				(width 0.1524)
				(type default)
			)
			(layer "B.SilkS")
		)
		(fp_line
			(start 0.67945 -0.305054)
			(end 0.12065 -0.305054)
			(stroke
				(width 0.1)
				(type default)
			)
			(layer "B.Fab")
		)
		(fp_line
			(start 0.12065 -0.305054)
			(end 0.12065 -0.2794)
			(stroke
				(width 0.1)
				(type default)
			)
			(layer "B.Fab")
		)
		(fp_line
			(start -0.12065 -0.3048)
			(end -0.67945 -0.3048)
			(stroke
				(width 0.1)
				(type default)
			)
			(layer "B.Fab")
		)
		(fp_line
			(start -0.67945 -0.3048)
			(end -0.67945 0.3048)
			(stroke
				(width 0.1)
				(type default)
			)
			(layer "B.Fab")
		)
		(fp_line
			(start 0.12065 -0.2794)
			(end -0.12065 -0.2794)
			(stroke
				(width 0.1)
				(type default)
			)
			(layer "B.Fab")
		)
		(fp_line
			(start -0.12065 -0.2794)
			(end -0.12065 -0.3048)
			(stroke
				(width 0.1)
				(type default)
			)
			(layer "B.Fab")
		)
		(fp_line
			(start 0.12065 0.2794)
			(end 0.12065 0.3048)
			(stroke
				(width 0.1)
				(type default)
			)
			(layer "B.Fab")
		)
		(fp_line
			(start -0.120396 0.2794)
			(end 0.12065 0.2794)
			(stroke
				(width 0.1)
				(type default)
			)
			(layer "B.Fab")
		)
		(fp_line
			(start 0.67945 0.3048)
			(end 0.67945 -0.305054)
			(stroke
				(width 0.1)
				(type default)
			)
			(layer "B.Fab")
		)
		(fp_line
			(start 0.12065 0.3048)
			(end 0.67945 0.3048)
			(stroke
				(width 0.1)
				(type default)
			)
			(layer "B.Fab")
		)
		(fp_line
			(start -0.120396 0.3048)
			(end -0.120396 0.2794)
			(stroke
				(width 0.1)
				(type default)
			)
			(layer "B.Fab")
		)
		(fp_line
			(start -0.67945 0.3048)
			(end -0.120396 0.3048)
			(stroke
				(width 0.1)
				(type default)
			)
			(layer "B.Fab")
		)
		(pad "1" smd circle
			(at 0.40005 0 270)
			(size 0 0)
			(layers "B.Cu" "B.Mask" "B.Paste")
			(net "SMB_VR_SENSOR_3V3AUX_SCL")
		)
		(pad "2" smd circle
			(at -0.40005 0 270)
			(size 0 0)
			(layers "B.Cu" "B.Mask" "B.Paste")
			(net "SMB_VR_3V3AUX_SCL_R0")
		)
	)
)
